(kicad_pcb
	(version 20260206)
	(generator "pcbnew")
	(generator_version "10.0")
	(general
		(thickness 1.6)
		(legacy_teardrops no)
	)
	(paper "A4")
	(title_block
		(title "Wiwynn_Tioga_Pass_MB.brd")
		(comment 1 "Tioga Pass / footprints 3850-3856 of 4770")
	)
	(layers
		(0 "F.Cu" signal "TOP")
		(4 "In1.Cu" signal "L2GND")
		(6 "In2.Cu" signal "L3")
		(8 "In3.Cu" signal "L4GND")
		(10 "In4.Cu" signal "L5")
		(12 "In5.Cu" signal "L6GND")
		(14 "In6.Cu" signal "L7VCC")
		(16 "In7.Cu" signal "L8VCC")
		(18 "In8.Cu" signal "L9GND")
		(20 "In9.Cu" signal "L10")
		(22 "In10.Cu" signal "L11GND")
		(24 "In11.Cu" signal "L12")
		(26 "In12.Cu" signal "L13GND")
		(2 "B.Cu" signal "BOTTOM")
		(9 "F.Adhes" user "F.Adhesive")
		(11 "B.Adhes" user "B.Adhesive")
		(13 "F.Paste" user "Package Geometry/Pastemask Top")
		(15 "B.Paste" user "Package Geometry/Pastemask Bottom")
		(5 "F.SilkS" user "Ref Des/Silkscreen Top")
		(7 "B.SilkS" user "Ref Des/Silkscreen Bottom")
		(1 "F.Mask" user "Board Geometry/Soldermask Top")
		(3 "B.Mask" user "Board Geometry/Soldermask Bottom")
		(17 "Dwgs.User" user "User.Drawings")
		(19 "Cmts.User" user "User.Comments")
		(21 "Eco1.User" user "User.Eco1")
		(23 "Eco2.User" user "User.Eco2")
		(25 "Edge.Cuts" user "Board Geometry/Outline")
		(27 "Margin" user)
		(31 "F.CrtYd" user "Package Geometry/Place Bound Top")
		(29 "B.CrtYd" user "Package Geometry/Place Bound Bottom")
		(35 "F.Fab" user "Ref Des/Assembly Top")
		(33 "B.Fab" user "Ref Des/Assembly Bottom")
	)
	(footprint ""
		(layer "B.Cu")
		(at 492.9886 -38.9636)
		(property "Reference" "R9W33"
			(at 0.8382 -0.67818 0)
			(unlocked yes)
			(layer "B.SilkS")
			(effects
				(font
					(size 0.4064 0.254)
					(thickness 0.1524)
				)
				(justify left mirror)
			)
		)
		(property "Value" ""
			(at 0 0 0)
			(layer "B.Fab")
			(effects
				(font
					(size 1.27 1.27)
				)
				(justify mirror)
			)
		)
		(duplicate_pad_numbers_are_jumpers no)
		(fp_poly
			(pts
				(xy 0.2794 -0.1016) (xy -0.2794 -0.1016) (xy -0.2794 0.9906) (xy 0.2794 0.9906)
			)
			(stroke
				(width 0)
				(type default)
			)
			(fill no)
			(layer "B.CrtYd")
		)
		(fp_line
			(start -0.2794 -0.1016)
			(end 0.2794 -0.1016)
			(stroke
				(width 0.1)
				(type default)
			)
			(layer "B.Fab")
		)
		(fp_line
			(start -0.2794 0.9906)
			(end -0.2794 -0.1016)
			(stroke
				(width 0.1)
				(type default)
			)
			(layer "B.Fab")
		)
		(fp_line
			(start 0.2794 -0.1016)
			(end 0.2794 0.9906)
			(stroke
				(width 0.1)
				(type default)
			)
			(layer "B.Fab")
		)
		(fp_line
			(start 0.2794 0.9906)
			(end -0.2794 0.9906)
			(stroke
				(width 0.1)
				(type default)
			)
			(layer "B.Fab")
		)
		(pad "1" smd rect
			(at 0 0 180)
			(size 0.508 0.508)
			(layers "B.Cu" "B.Mask" "B.Paste")
			(net "P3V3_STBY")
		)
		(pad "2" smd rect
			(at 0 0.889 180)
			(size 0.508 0.508)
			(layers "B.Cu" "B.Mask" "B.Paste")
			(net "SP1_BMC_HOST_UART_RX")
		)
		(zone
			(layer "B.Cu")
			(hatch none 0.5)
			(connect_pads
				(clearance 0)
			)
			(min_thickness 0.25)
			(keepout
				(tracks allowed)
				(vias not_allowed)
				(pads allowed)
				(copperpour not_allowed)
				(footprints allowed)
			)
			(placement
				(enabled no)
				(sheetname "")
			)
			(fill
				(thermal_gap 0.5)
				(thermal_bridge_width 0.5)
				(island_removal_mode 0)
			)
			(polygon
				(pts
					(xy 493.2426 -38.7096) (xy 492.7346 -38.7096) (xy 492.7346 -38.3286) (xy 493.2426 -38.3286)
				)
			)
		)
		(zone
			(layer "B.Cu")
			(hatch none 0.5)
			(connect_pads
				(clearance 0)
			)
			(min_thickness 0.25)
			(keepout
				(tracks not_allowed)
				(vias allowed)
				(pads allowed)
				(copperpour not_allowed)
				(footprints allowed)
			)
			(placement
				(enabled no)
				(sheetname "")
			)
			(fill
				(thermal_gap 0.5)
				(thermal_bridge_width 0.5)
				(island_removal_mode 0)
			)
			(polygon
				(pts
					(xy 493.2426 -38.3286) (xy 492.7346 -38.3286) (xy 492.7346 -38.7096) (xy 493.2426 -38.7096)
				)
			)
		)
	)
	(footprint ""
		(layer "B.Cu")
		(at 26.8478 -30.099 180)
		(property "Reference" "R9T8"
			(at 0 0 0)
			(layer "B.SilkS")
			(hide yes)
			(effects
				(font
					(size 1.27 1.27)
				)
				(justify mirror)
			)
		)
		(property "Value" ""
			(at 0 0 0)
			(layer "B.Fab")
			(effects
				(font
					(size 1.27 1.27)
				)
				(justify mirror)
			)
		)
		(duplicate_pad_numbers_are_jumpers no)
		(fp_rect
			(start -0.2794 -0.1016)
			(end 0.2794 0.9906)
			(stroke
				(width 0)
				(type default)
			)
			(fill no)
			(layer "B.CrtYd")
		)
		(fp_line
			(start 0.2794 0.9906)
			(end -0.2794 0.9906)
			(stroke
				(width 0.1)
				(type default)
			)
			(layer "B.Fab")
		)
		(fp_line
			(start 0.2794 -0.1016)
			(end 0.2794 0.9906)
			(stroke
				(width 0.1)
				(type default)
			)
			(layer "B.Fab")
		)
		(fp_line
			(start -0.2794 0.9906)
			(end -0.2794 -0.1016)
			(stroke
				(width 0.1)
				(type default)
			)
			(layer "B.Fab")
		)
		(fp_line
			(start -0.2794 -0.1016)
			(end 0.2794 -0.1016)
			(stroke
				(width 0.1)
				(type default)
			)
			(layer "B.Fab")
		)
		(pad "1" smd rect
			(at 0 0)
			(size 0.508 0.508)
			(layers "B.Cu" "B.Mask" "B.Paste")
			(net "FM_MATED_IN_N")
		)
		(pad "2" smd rect
			(at 0 0.889)
			(size 0.508 0.508)
			(layers "B.Cu" "B.Mask" "B.Paste")
			(net "GND")
		)
		(zone
			(layer "B.Cu")
			(hatch none 0.5)
			(connect_pads
				(clearance 0)
			)
			(min_thickness 0.25)
			(keepout
				(tracks not_allowed)
				(vias allowed)
				(pads allowed)
				(copperpour not_allowed)
				(footprints allowed)
			)
			(placement
				(enabled no)
				(sheetname "")
			)
			(fill
				(thermal_gap 0.5)
				(thermal_bridge_width 0.5)
				(island_removal_mode 0)
			)
			(polygon
				(pts
					(xy 27.1018 -30.353) (xy 27.1018 -30.734) (xy 26.5938 -30.734) (xy 26.5938 -30.353)
				)
			)
		)
		(zone
			(layer "B.Cu")
			(hatch none 0.5)
			(connect_pads
				(clearance 0)
			)
			(min_thickness 0.25)
			(keepout
				(tracks allowed)
				(vias not_allowed)
				(pads allowed)
				(copperpour not_allowed)
				(footprints allowed)
			)
			(placement
				(enabled no)
				(sheetname "")
			)
			(fill
				(thermal_gap 0.5)
				(thermal_bridge_width 0.5)
				(island_removal_mode 0)
			)
			(polygon
				(pts
					(xy 27.1018 -30.353) (xy 27.1018 -30.734) (xy 26.5938 -30.734) (xy 26.5938 -30.353)
				)
			)
		)
	)
	(footprint ""
		(layer "B.Cu")
		(at 166.116 -87.757)
		(property "Reference" "R6P7"
			(at 0 0 0)
			(layer "B.SilkS")
			(hide yes)
			(effects
				(font
					(size 1.27 1.27)
				)
				(justify mirror)
			)
		)
		(property "Value" ""
			(at 0 0 0)
			(layer "B.Fab")
			(effects
				(font
					(size 1.27 1.27)
				)
				(justify mirror)
			)
		)
		(duplicate_pad_numbers_are_jumpers no)
		(fp_poly
			(pts
				(xy 0.2794 -0.1016) (xy -0.2794 -0.1016) (xy -0.2794 0.9906) (xy 0.2794 0.9906)
			)
			(stroke
				(width 0)
				(type default)
			)
			(fill no)
			(layer "B.CrtYd")
		)
		(fp_line
			(start -0.2794 -0.1016)
			(end 0.2794 -0.1016)
			(stroke
				(width 0.1)
				(type default)
			)
			(layer "B.Fab")
		)
		(fp_line
			(start -0.2794 0.9906)
			(end -0.2794 -0.1016)
			(stroke
				(width 0.1)
				(type default)
			)
			(layer "B.Fab")
		)
		(fp_line
			(start 0.2794 -0.1016)
			(end 0.2794 0.9906)
			(stroke
				(width 0.1)
				(type default)
			)
			(layer "B.Fab")
		)
		(fp_line
			(start 0.2794 0.9906)
			(end -0.2794 0.9906)
			(stroke
				(width 0.1)
				(type default)
			)
			(layer "B.Fab")
		)
		(pad "1" smd rect
			(at 0 0 180)
			(size 0.508 0.508)
			(layers "B.Cu" "B.Mask" "B.Paste")
			(net "CLK_100M_CPU1_BCLK1_DP")
		)
		(pad "2" smd rect
			(at 0 0.889 180)
			(size 0.508 0.508)
			(layers "B.Cu" "B.Mask" "B.Paste")
			(net "GND")
		)
		(zone
			(layer "B.Cu")
			(hatch none 0.5)
			(connect_pads
				(clearance 0)
			)
			(min_thickness 0.25)
			(keepout
				(tracks allowed)
				(vias not_allowed)
				(pads allowed)
				(copperpour not_allowed)
				(footprints allowed)
			)
			(placement
				(enabled no)
				(sheetname "")
			)
			(fill
				(thermal_gap 0.5)
				(thermal_bridge_width 0.5)
				(island_removal_mode 0)
			)
			(polygon
				(pts
					(xy 166.37 -87.503) (xy 165.862 -87.503) (xy 165.862 -87.122) (xy 166.37 -87.122)
				)
			)
		)
		(zone
			(layer "B.Cu")
			(hatch none 0.5)
			(connect_pads
				(clearance 0)
			)
			(min_thickness 0.25)
			(keepout
				(tracks not_allowed)
				(vias allowed)
				(pads allowed)
				(copperpour not_allowed)
				(footprints allowed)
			)
			(placement
				(enabled no)
				(sheetname "")
			)
			(fill
				(thermal_gap 0.5)
				(thermal_bridge_width 0.5)
				(island_removal_mode 0)
			)
			(polygon
				(pts
					(xy 166.37 -87.122) (xy 165.862 -87.122) (xy 165.862 -87.503) (xy 166.37 -87.503)
				)
			)
		)
	)
	(footprint ""
		(layer "B.Cu")
		(at 487.172 -139.6746 90)
		(property "Reference" "R1L38"
			(at 0 0 90)
			(layer "B.SilkS")
			(hide yes)
			(effects
				(font
					(size 1.27 1.27)
				)
				(justify mirror)
			)
		)
		(property "Value" ""
			(at 0 0 90)
			(layer "B.Fab")
			(effects
				(font
					(size 1.27 1.27)
				)
				(justify mirror)
			)
		)
		(duplicate_pad_numbers_are_jumpers no)
		(fp_poly
			(pts
				(xy 0.2794 -0.1016) (xy -0.2794 -0.1016) (xy -0.2794 0.9906) (xy 0.2794 0.9906)
			)
			(stroke
				(width 0)
				(type default)
			)
			(fill no)
			(layer "B.CrtYd")
		)
		(fp_line
			(start 0.2794 -0.1016)
			(end 0.2794 0.9906)
			(stroke
				(width 0.1)
				(type default)
			)
			(layer "B.Fab")
		)
		(fp_line
			(start -0.2794 -0.1016)
			(end 0.2794 -0.1016)
			(stroke
				(width 0.1)
				(type default)
			)
			(layer "B.Fab")
		)
		(fp_line
			(start 0.2794 0.9906)
			(end -0.2794 0.9906)
			(stroke
				(width 0.1)
				(type default)
			)
			(layer "B.Fab")
		)
		(fp_line
			(start -0.2794 0.9906)
			(end -0.2794 -0.1016)
			(stroke
				(width 0.1)
				(type default)
			)
			(layer "B.Fab")
		)
		(pad "1" smd rect
			(at 0 0 270)
			(size 0.508 0.508)
			(layers "B.Cu" "B.Mask" "B.Paste")
			(net "P3V3_STBY")
		)
		(pad "2" smd rect
			(at 0 0.889 270)
			(size 0.508 0.508)
			(layers "B.Cu" "B.Mask" "B.Paste")
			(net "FM_POST_CARD_PRES_BMC_N")
		)
		(zone
			(layer "B.Cu")
			(hatch none 0.5)
			(connect_pads
				(clearance 0)
			)
			(min_thickness 0.25)
			(keepout
				(tracks allowed)
				(vias not_allowed)
				(pads allowed)
				(copperpour not_allowed)
				(footprints allowed)
			)
			(placement
				(enabled no)
				(sheetname "")
			)
			(fill
				(thermal_gap 0.5)
				(thermal_bridge_width 0.5)
				(island_removal_mode 0)
			)
			(polygon
				(pts
					(xy 487.426 -139.9286) (xy 487.426 -139.4206) (xy 487.807 -139.4206) (xy 487.807 -139.9286)
				)
			)
		)
		(zone
			(layer "B.Cu")
			(hatch none 0.5)
			(connect_pads
				(clearance 0)
			)
			(min_thickness 0.25)
			(keepout
				(tracks not_allowed)
				(vias allowed)
				(pads allowed)
				(copperpour not_allowed)
				(footprints allowed)
			)
			(placement
				(enabled no)
				(sheetname "")
			)
			(fill
				(thermal_gap 0.5)
				(thermal_bridge_width 0.5)
				(island_removal_mode 0)
			)
			(polygon
				(pts
					(xy 487.807 -139.9286) (xy 487.807 -139.4206) (xy 487.426 -139.4206) (xy 487.426 -139.9286)
				)
			)
		)
	)
	(footprint ""
		(layer "B.Cu")
		(at 4.25704 -12.573 90)
		(property "Reference" "C1G13"
			(at 0 0 90)
			(layer "B.SilkS")
			(hide yes)
			(effects
				(font
					(size 1.27 1.27)
				)
				(justify mirror)
			)
		)
		(property "Value" ""
			(at 0 0 90)
			(layer "B.Fab")
			(effects
				(font
					(size 1.27 1.27)
				)
				(justify mirror)
			)
		)
		(duplicate_pad_numbers_are_jumpers no)
		(fp_poly
			(pts
				(xy -0.3048 -0.1016) (xy -0.3048 0.9906) (xy 0.3048 0.9906) (xy 0.3048 -0.1016)
			)
			(stroke
				(width 0)
				(type default)
			)
			(fill no)
			(layer "B.CrtYd")
		)
		(fp_line
			(start 0.3048 -0.1016)
			(end 0.3048 0.9906)
			(stroke
				(width 0.1)
				(type default)
			)
			(layer "B.Fab")
		)
		(fp_line
			(start -0.3048 -0.1016)
			(end 0.3048 -0.1016)
			(stroke
				(width 0.1)
				(type default)
			)
			(layer "B.Fab")
		)
		(fp_line
			(start 0.3048 0.9906)
			(end -0.3048 0.9906)
			(stroke
				(width 0.1)
				(type default)
			)
			(layer "B.Fab")
		)
		(fp_line
			(start -0.3048 0.9906)
			(end -0.3048 -0.1016)
			(stroke
				(width 0.1)
				(type default)
			)
			(layer "B.Fab")
		)
		(pad "1" smd rect
			(at 0 0 270)
			(size 0.508 0.508)
			(layers "B.Cu" "B.Mask" "B.Paste")
			(net "VR_FET_SW_P12V_STBY_PVDDQ_GHJ")
		)
		(pad "2" smd rect
			(at 0 0.889 270)
			(size 0.508 0.508)
			(layers "B.Cu" "B.Mask" "B.Paste")
			(net "GND")
		)
		(zone
			(layer "B.Cu")
			(hatch none 0.5)
			(connect_pads
				(clearance 0)
			)
			(min_thickness 0.25)
			(keepout
				(tracks allowed)
				(vias not_allowed)
				(pads allowed)
				(copperpour not_allowed)
				(footprints allowed)
			)
			(placement
				(enabled no)
				(sheetname "")
			)
			(fill
				(thermal_gap 0.5)
				(thermal_bridge_width 0.5)
				(island_removal_mode 0)
			)
			(polygon
				(pts
					(xy 4.51104 -12.827) (xy 4.51104 -12.319) (xy 4.89204 -12.319) (xy 4.89204 -12.827)
				)
			)
		)
		(zone
			(layer "B.Cu")
			(hatch none 0.5)
			(connect_pads
				(clearance 0)
			)
			(min_thickness 0.25)
			(keepout
				(tracks not_allowed)
				(vias allowed)
				(pads allowed)
				(copperpour not_allowed)
				(footprints allowed)
			)
			(placement
				(enabled no)
				(sheetname "")
			)
			(fill
				(thermal_gap 0.5)
				(thermal_bridge_width 0.5)
				(island_removal_mode 0)
			)
			(polygon
				(pts
					(xy 4.89204 -12.827) (xy 4.89204 -12.319) (xy 4.51104 -12.319) (xy 4.51104 -12.827)
				)
			)
		)
	)
	(footprint ""
		(layer "B.Cu")
		(at 228.1174 -87.5792 90)
		(property "Reference" "R4C1"
			(at 0.8382 -0.67818 90)
			(unlocked yes)
			(layer "B.SilkS")
			(effects
				(font
					(size 0.4064 0.254)
					(thickness 0.1524)
				)
				(justify left mirror)
			)
		)
		(property "Value" ""
			(at 0 0 90)
			(layer "B.Fab")
			(effects
				(font
					(size 1.27 1.27)
				)
				(justify mirror)
			)
		)
		(duplicate_pad_numbers_are_jumpers no)
		(fp_poly
			(pts
				(xy 0.2794 -0.1016) (xy -0.2794 -0.1016) (xy -0.2794 0.9906) (xy 0.2794 0.9906)
			)
			(stroke
				(width 0)
				(type default)
			)
			(fill no)
			(layer "B.CrtYd")
		)
		(fp_line
			(start 0.2794 -0.1016)
			(end 0.2794 0.9906)
			(stroke
				(width 0.1)
				(type default)
			)
			(layer "B.Fab")
		)
		(fp_line
			(start -0.2794 -0.1016)
			(end 0.2794 -0.1016)
			(stroke
				(width 0.1)
				(type default)
			)
			(layer "B.Fab")
		)
		(fp_line
			(start 0.2794 0.9906)
			(end -0.2794 0.9906)
			(stroke
				(width 0.1)
				(type default)
			)
			(layer "B.Fab")
		)
		(fp_line
			(start -0.2794 0.9906)
			(end -0.2794 -0.1016)
			(stroke
				(width 0.1)
				(type default)
			)
			(layer "B.Fab")
		)
		(pad "1" smd rect
			(at 0 0 270)
			(size 0.508 0.508)
			(layers "B.Cu" "B.Mask" "B.Paste")
			(net "VSENSE_PVSA_CPU0_N")
		)
		(pad "2" smd rect
			(at 0 0.889 270)
			(size 0.508 0.508)
			(layers "B.Cu" "B.Mask" "B.Paste")
			(net "GND")
		)
		(zone
			(layer "B.Cu")
			(hatch none 0.5)
			(connect_pads
				(clearance 0)
			)
			(min_thickness 0.25)
			(keepout
				(tracks allowed)
				(vias not_allowed)
				(pads allowed)
				(copperpour not_allowed)
				(footprints allowed)
			)
			(placement
				(enabled no)
				(sheetname "")
			)
			(fill
				(thermal_gap 0.5)
				(thermal_bridge_width 0.5)
				(island_removal_mode 0)
			)
			(polygon
				(pts
					(xy 228.3714 -87.8332) (xy 228.3714 -87.3252) (xy 228.7524 -87.3252) (xy 228.7524 -87.8332)
				)
			)
		)
		(zone
			(layer "B.Cu")
			(hatch none 0.5)
			(connect_pads
				(clearance 0)
			)
			(min_thickness 0.25)
			(keepout
				(tracks not_allowed)
				(vias allowed)
				(pads allowed)
				(copperpour not_allowed)
				(footprints allowed)
			)
			(placement
				(enabled no)
				(sheetname "")
			)
			(fill
				(thermal_gap 0.5)
				(thermal_bridge_width 0.5)
				(island_removal_mode 0)
			)
			(polygon
				(pts
					(xy 228.7524 -87.8332) (xy 228.7524 -87.3252) (xy 228.3714 -87.3252) (xy 228.3714 -87.8332)
				)
			)
		)
	)
	(footprint ""
		(layer "B.Cu")
		(at 414.5407 -37.76218)
		(property "Reference" "C25W28"
			(at 0.8382 -0.67818 0)
			(unlocked yes)
			(layer "B.SilkS")
			(effects
				(font
					(size 0.4064 0.254)
					(thickness 0.1524)
				)
				(justify left mirror)
			)
		)
		(property "Value" ""
			(at 0 0 0)
			(layer "B.Fab")
			(effects
				(font
					(size 1.27 1.27)
				)
				(justify mirror)
			)
		)
		(duplicate_pad_numbers_are_jumpers no)
		(fp_poly
			(pts
				(xy -0.3048 -0.1016) (xy -0.3048 0.9906) (xy 0.3048 0.9906) (xy 0.3048 -0.1016)
			)
			(stroke
				(width 0)
				(type default)
			)
			(fill no)
			(layer "B.CrtYd")
		)
		(fp_line
			(start -0.3048 -0.1016)
			(end 0.3048 -0.1016)
			(stroke
				(width 0.1)
				(type default)
			)
			(layer "B.Fab")
		)
		(fp_line
			(start -0.3048 0.9906)
			(end -0.3048 -0.1016)
			(stroke
				(width 0.1)
				(type default)
			)
			(layer "B.Fab")
		)
		(fp_line
			(start 0.3048 -0.1016)
			(end 0.3048 0.9906)
			(stroke
				(width 0.1)
				(type default)
			)
			(layer "B.Fab")
		)
		(fp_line
			(start 0.3048 0.9906)
			(end -0.3048 0.9906)
			(stroke
				(width 0.1)
				(type default)
			)
			(layer "B.Fab")
		)
		(pad "1" smd rect
			(at 0 0 180)
			(size 0.508 0.508)
			(layers "B.Cu" "B.Mask" "B.Paste")
			(net "P1V15_AUX_BMC")
		)
		(pad "2" smd rect
			(at 0 0.889 180)
			(size 0.508 0.508)
			(layers "B.Cu" "B.Mask" "B.Paste")
			(net "GND")
		)
		(zone
			(layer "B.Cu")
			(hatch none 0.5)
			(connect_pads
				(clearance 0)
			)
			(min_thickness 0.25)
			(keepout
				(tracks allowed)
				(vias not_allowed)
				(pads allowed)
				(copperpour not_allowed)
				(footprints allowed)
			)
			(placement
				(enabled no)
				(sheetname "")
			)
			(fill
				(thermal_gap 0.5)
				(thermal_bridge_width 0.5)
				(island_removal_mode 0)
			)
			(polygon
				(pts
					(xy 414.7947 -37.50818) (xy 414.2867 -37.50818) (xy 414.2867 -37.12718) (xy 414.7947 -37.12718)
				)
			)
		)
		(zone
			(layer "B.Cu")
			(hatch none 0.5)
			(connect_pads
				(clearance 0)
			)
			(min_thickness 0.25)
			(keepout
				(tracks not_allowed)
				(vias allowed)
				(pads allowed)
				(copperpour not_allowed)
				(footprints allowed)
			)
			(placement
				(enabled no)
				(sheetname "")
			)
			(fill
				(thermal_gap 0.5)
				(thermal_bridge_width 0.5)
				(island_removal_mode 0)
			)
			(polygon
				(pts
					(xy 414.7947 -37.12718) (xy 414.2867 -37.12718) (xy 414.2867 -37.50818) (xy 414.7947 -37.50818)
				)
			)
		)
	)
)
